FILE_TYPE = CONNECTIVITY;
{Allegro Design Entry HDL 17.2-2016 S081 (4005846) 1/11/2022}
"PAGE_NUMBER" = 26;
0"NC";
1"M_G_CPU0_SA_CA<6:0>";
2"M_G_CPU0_SA_CS_N<3:0>";
3"M_G_CPU0_SA_DQS_DN<9:0>";
4"M_G_CPU0_SA_DQS_DP<9:0>";
5"M_G_CPU0_SB_CA<6:0>";
6"M_G_CPU0_SB_CS_N<3:0>";
7"M_G_CPU0_SB_DQS_DN<9:0>";
8"M_G_CPU0_SB_DQS_DP<9:0>";
9"M_G_CPU0_SB_CB<7:0>";
10"M_G_CPU0_SB_DQ<31:0>";
11"M_G_CPU0_SA_CB<7:0>";
12"M_G_CPU0_SA_DQ<31:0>";
13"M_G_CPU0_CLK_DP<1:0>";
14"M_G_CPU0_CLK_DN<1:0>";
15"M_G_CPU0_CLK_DN<1>";
16"M_G_CPU0_CLK_DN<0>";
17"M_G_CPU0_CLK_DP<1>";
18"M_G_CPU0_CLK_DP<0>";
19"M_G_CPU0_SA_DQ<31>";
20"M_G_CPU0_SA_DQ<30>";
21"M_G_CPU0_SA_DQ<29>";
22"M_G_CPU0_SA_DQ<28>";
23"M_G_CPU0_SA_DQ<27>";
24"M_G_CPU0_SA_DQ<26>";
25"M_G_CPU0_SA_DQ<25>";
26"M_G_CPU0_SA_DQ<24>";
27"M_G_CPU0_SA_DQ<23>";
28"M_G_CPU0_SA_DQ<22>";
29"M_G_CPU0_SA_DQ<21>";
30"M_G_CPU0_SA_DQ<20>";
31"M_G_CPU0_SA_DQ<19>";
32"M_G_CPU0_SA_DQ<18>";
33"M_G_CPU0_SA_DQ<17>";
34"M_G_CPU0_SA_DQ<16>";
35"M_G_CPU0_SA_DQ<15>";
36"M_G_CPU0_SA_DQ<14>";
37"M_G_CPU0_SA_DQ<13>";
38"M_G_CPU0_SA_DQ<12>";
39"M_G_CPU0_SA_DQ<11>";
40"M_G_CPU0_SA_DQ<10>";
41"M_G_CPU0_SA_DQ<9>";
42"M_G_CPU0_SA_DQ<8>";
43"M_G_CPU0_SA_DQ<7>";
44"M_G_CPU0_SA_DQ<6>";
45"M_G_CPU0_SA_DQ<5>";
46"M_G_CPU0_SA_DQ<4>";
47"M_G_CPU0_SA_DQ<3>";
48"M_G_CPU0_SA_DQ<2>";
49"M_G_CPU0_SA_DQ<1>";
50"M_G_CPU0_SA_DQ<0>";
51"M_G_CPU0_SA_CB<7>";
52"M_G_CPU0_SA_CB<6>";
53"M_G_CPU0_SA_CB<5>";
54"M_G_CPU0_SA_CB<4>";
55"M_G_CPU0_SA_CB<3>";
56"M_G_CPU0_SA_CB<2>";
57"M_G_CPU0_SA_CB<1>";
58"M_G_CPU0_SA_CB<0>";
59"M_G_CPU0_SB_DQ<31>";
60"M_G_CPU0_SB_DQ<30>";
61"M_G_CPU0_SB_DQ<29>";
62"M_G_CPU0_SB_DQ<28>";
63"M_G_CPU0_SB_DQ<27>";
64"M_G_CPU0_SB_DQ<26>";
65"M_G_CPU0_SB_DQ<25>";
66"M_G_CPU0_SB_DQ<24>";
67"M_G_CPU0_SB_DQ<23>";
68"M_G_CPU0_SB_DQ<22>";
69"M_G_CPU0_SB_DQ<21>";
70"M_G_CPU0_SB_DQ<20>";
71"M_G_CPU0_SB_DQ<19>";
72"M_G_CPU0_SB_DQ<18>";
73"M_G_CPU0_SB_DQ<17>";
74"M_G_CPU0_SB_DQ<16>";
75"M_G_CPU0_SB_DQ<15>";
76"M_G_CPU0_SB_DQ<14>";
77"M_G_CPU0_SB_DQ<13>";
78"M_G_CPU0_SB_DQ<12>";
79"M_G_CPU0_SB_DQ<11>";
80"M_G_CPU0_SB_DQ<10>";
81"M_G_CPU0_SB_DQ<9>";
82"M_G_CPU0_SB_DQ<8>";
83"M_G_CPU0_SB_DQ<7>";
84"M_G_CPU0_SB_DQ<6>";
85"M_G_CPU0_SB_DQ<5>";
86"M_G_CPU0_SB_DQ<4>";
87"M_G_CPU0_SB_DQ<3>";
88"M_G_CPU0_SB_DQ<2>";
89"M_G_CPU0_SB_DQ<1>";
90"M_G_CPU0_SB_DQ<0>";
91"M_G_CPU0_SB_CB<7>";
92"M_G_CPU0_SB_CB<6>";
93"M_G_CPU0_SB_CB<5>";
94"M_G_CPU0_SB_CB<4>";
95"M_G_CPU0_SB_CB<3>";
96"M_G_CPU0_SB_CB<2>";
97"M_G_CPU0_SB_CB<1>";
98"M_G_CPU0_SB_CB<0>";
99"M_G_CPU0_SB_PAR";
100"M_G_CPU0_SB_DQS_DP<0>";
101"M_G_CPU0_SB_DQS_DP<1>";
102"M_G_CPU0_SB_DQS_DP<2>";
103"M_G_CPU0_SB_DQS_DP<3>";
104"M_G_CPU0_SB_DQS_DP<4>";
105"M_G_CPU0_SB_DQS_DP<5>";
106"M_G_CPU0_SB_DQS_DP<6>";
107"M_G_CPU0_SB_DQS_DP<7>";
108"M_G_CPU0_SB_DQS_DP<8>";
109"M_G_CPU0_SB_DQS_DP<9>";
110"M_G_CPU0_SB_DQS_DN<0>";
111"M_G_CPU0_SB_DQS_DN<1>";
112"M_G_CPU0_SB_DQS_DN<2>";
113"M_G_CPU0_SB_DQS_DN<3>";
114"M_G_CPU0_SB_DQS_DN<4>";
115"M_G_CPU0_SB_DQS_DN<5>";
116"M_G_CPU0_SB_DQS_DN<6>";
117"M_G_CPU0_SB_DQS_DN<7>";
118"M_G_CPU0_SB_DQS_DN<8>";
119"M_G_CPU0_SB_DQS_DN<9>";
120"M_G_CPU0_SB_CS_N<0>";
121"M_G_CPU0_SB_CS_N<1>";
122"M_G_CPU0_SB_CS_N<2>";
123"M_G_CPU0_SB_CS_N<3>";
124"M_G_CPU0_SB_CA<0>";
125"M_G_CPU0_SB_CA<1>";
126"M_G_CPU0_SB_CA<2>";
127"M_G_CPU0_SB_CA<3>";
128"M_G_CPU0_SB_CA<4>";
129"M_G_CPU0_SB_CA<5>";
130"M_G_CPU0_SB_CA<6>";
131"M_G_CPU0_SA_PAR";
132"M_G_CPU0_SA_DQS_DP<0>";
133"M_G_CPU0_SA_DQS_DP<1>";
134"M_G_CPU0_SA_DQS_DP<2>";
135"M_G_CPU0_SA_DQS_DP<3>";
136"M_G_CPU0_SA_DQS_DP<4>";
137"M_G_CPU0_SA_DQS_DP<5>";
138"M_G_CPU0_SA_DQS_DP<6>";
139"M_G_CPU0_SA_DQS_DP<7>";
140"M_G_CPU0_SA_DQS_DP<8>";
141"M_G_CPU0_SA_DQS_DP<9>";
142"M_G_CPU0_SA_DQS_DN<0>";
143"M_G_CPU0_SA_DQS_DN<1>";
144"M_G_CPU0_SA_DQS_DN<2>";
145"M_G_CPU0_SA_DQS_DN<3>";
146"M_G_CPU0_SA_DQS_DN<4>";
147"M_G_CPU0_SA_DQS_DN<5>";
148"M_G_CPU0_SA_DQS_DN<6>";
149"M_G_CPU0_SA_DQS_DN<7>";
150"M_G_CPU0_SA_DQS_DN<8>";
151"M_G_CPU0_SA_DQS_DN<9>";
152"M_G_CPU0_SA_CS_N<0>";
153"M_G_CPU0_SA_CS_N<1>";
154"M_G_CPU0_SA_CS_N<2>";
155"M_G_CPU0_SA_CS_N<3>";
156"M_G_CPU0_SA_CA<0>";
157"M_G_CPU0_SA_CA<1>";
158"M_G_CPU0_SA_CA<2>";
159"M_G_CPU0_SA_CA<3>";
160"M_G_CPU0_SA_CA<4>";
161"M_G_CPU0_SA_CA<5>";
162"M_G_CPU0_SA_CA<6>";
163"M_G_CPU0_SB_RSP<0>";
164"M_G_CPU0_SB_RSP<1>";
165"M_G_CPU0_SA_RSP<0>";
166"M_G_CPU0_SA_RSP<1>";
167"M_G_CPU0_ALERT_N";
%"TAP"
"1","(3225,400)","0","standard","I100";
;
CDS_LIB"standard"
BODY_TYPE"PLUMBING"
HDL_TAP"TRUE";
"B \NAC \NWC"6;
"S \NAC"
BN"2"122;
%"TAP"
"1","(3225,650)","0","standard","I101";
;
CDS_LIB"standard"
BODY_TYPE"PLUMBING"
HDL_TAP"TRUE";
"B \NAC \NWC"2;
"S \NAC"
BN"1"153;
%"TAP"
"1","(3225,700)","0","standard","I102";
;
CDS_LIB"standard"
BODY_TYPE"PLUMBING"
HDL_TAP"TRUE";
"B \NAC \NWC"2;
"S \NAC"
BN"2"154;
%"TAP"
"1","(3225,600)","0","standard","I103";
;
CDS_LIB"standard"
BODY_TYPE"PLUMBING"
HDL_TAP"TRUE";
"B \NAC \NWC"2;
"S \NAC"
BN"0"152;
%"TAP"
"1","(3225,750)","0","standard","I104";
;
CDS_LIB"standard"
BODY_TYPE"PLUMBING"
HDL_TAP"TRUE";
"B \NAC \NWC"2;
"S \NAC"
BN"3"155;
%"TAP"
"1","(3225,950)","0","standard","I105";
;
CDS_LIB"standard"
BODY_TYPE"PLUMBING"
HDL_TAP"TRUE";
"B \NAC \NWC"5;
"S \NAC"
BN"0"124;
%"TAP"
"1","(3225,1050)","0","standard","I106";
;
CDS_LIB"standard"
BODY_TYPE"PLUMBING"
HDL_TAP"TRUE";
"B \NAC \NWC"5;
"S \NAC"
BN"2"126;
%"TAP"
"1","(3225,1000)","0","standard","I107";
;
CDS_LIB"standard"
BODY_TYPE"PLUMBING"
HDL_TAP"TRUE";
"B \NAC \NWC"5;
"S \NAC"
BN"1"125;
%"TAP"
"1","(3225,1200)","0","standard","I108";
;
CDS_LIB"standard"
BODY_TYPE"PLUMBING"
HDL_TAP"TRUE";
"B \NAC \NWC"5;
"S \NAC"
BN"5"129;
%"TAP"
"1","(3225,1100)","0","standard","I109";
;
CDS_LIB"standard"
BODY_TYPE"PLUMBING"
HDL_TAP"TRUE";
"B \NAC \NWC"5;
"S \NAC"
BN"3"127;
%"TAP"
"1","(3225,1150)","0","standard","I110";
;
CDS_LIB"standard"
BODY_TYPE"PLUMBING"
HDL_TAP"TRUE";
"B \NAC \NWC"5;
"S \NAC"
BN"4"128;
%"TAP"
"1","(3225,1250)","0","standard","I111";
;
CDS_LIB"standard"
BODY_TYPE"PLUMBING"
HDL_TAP"TRUE";
"B \NAC \NWC"5;
"S \NAC"
BN"6"130;
%"TAP"
"1","(3225,1450)","0","standard","I112";
;
CDS_LIB"standard"
BODY_TYPE"PLUMBING"
HDL_TAP"TRUE";
"B \NAC \NWC"1;
"S \NAC"
BN"0"156;
%"TAP"
"1","(3225,1550)","0","standard","I113";
;
CDS_LIB"standard"
BODY_TYPE"PLUMBING"
HDL_TAP"TRUE";
"B \NAC \NWC"1;
"S \NAC"
BN"2"158;
%"TAP"
"1","(3225,1500)","0","standard","I114";
;
CDS_LIB"standard"
BODY_TYPE"PLUMBING"
HDL_TAP"TRUE";
"B \NAC \NWC"1;
"S \NAC"
BN"1"157;
%"TAP"
"1","(3225,1600)","0","standard","I115";
;
CDS_LIB"standard"
BODY_TYPE"PLUMBING"
HDL_TAP"TRUE";
"B \NAC \NWC"1;
"S \NAC"
BN"3"159;
%"TAP"
"1","(3225,1700)","0","standard","I116";
;
CDS_LIB"standard"
BODY_TYPE"PLUMBING"
HDL_TAP"TRUE";
"B \NAC \NWC"1;
"S \NAC"
BN"5"161;
%"TAP"
"1","(3225,1650)","0","standard","I117";
;
CDS_LIB"standard"
BODY_TYPE"PLUMBING"
HDL_TAP"TRUE";
"B \NAC \NWC"1;
"S \NAC"
BN"4"160;
%"TAP"
"1","(3225,1750)","0","standard","I118";
;
CDS_LIB"standard"
BODY_TYPE"PLUMBING"
HDL_TAP"TRUE";
"B \NAC \NWC"1;
"S \NAC"
BN"6"162;
%"TAP"
"1","(3225,1900)","0","standard","I119";
;
CDS_LIB"standard"
BODY_TYPE"PLUMBING"
HDL_TAP"TRUE";
"B \NAC \NWC"7;
"S \NAC"
BN"0"110;
%"TAP"
"1","(-200,300)","2","standard","I12";
;
CDS_LIB"standard"
BODY_TYPE"PLUMBING"
HDL_TAP"TRUE";
"B \NAC \NWC"9;
"S \NAC"
BN"4"94;
%"TAP"
"1","(3225,1950)","0","standard","I120";
;
CDS_LIB"standard"
BODY_TYPE"PLUMBING"
HDL_TAP"TRUE";
"B \NAC \NWC"7;
"S \NAC"
BN"1"111;
%"TAP"
"1","(3225,2000)","0","standard","I121";
;
CDS_LIB"standard"
BODY_TYPE"PLUMBING"
HDL_TAP"TRUE";
"B \NAC \NWC"7;
"S \NAC"
BN"2"112;
%"TAP"
"1","(3225,2050)","0","standard","I122";
;
CDS_LIB"standard"
BODY_TYPE"PLUMBING"
HDL_TAP"TRUE";
"B \NAC \NWC"7;
"S \NAC"
BN"3"113;
%"TAP"
"1","(3225,2100)","0","standard","I123";
;
CDS_LIB"standard"
BODY_TYPE"PLUMBING"
HDL_TAP"TRUE";
"B \NAC \NWC"7;
"S \NAC"
BN"4"114;
%"TAP"
"1","(3225,2200)","0","standard","I124";
;
CDS_LIB"standard"
BODY_TYPE"PLUMBING"
HDL_TAP"TRUE";
"B \NAC \NWC"7;
"S \NAC"
BN"6"116;
%"TAP"
"1","(3225,2150)","0","standard","I125";
;
CDS_LIB"standard"
BODY_TYPE"PLUMBING"
HDL_TAP"TRUE";
"B \NAC \NWC"7;
"S \NAC"
BN"5"115;
%"TAP"
"1","(3225,2350)","0","standard","I126";
;
CDS_LIB"standard"
BODY_TYPE"PLUMBING"
HDL_TAP"TRUE";
"B \NAC \NWC"7;
"S \NAC"
BN"9"119;
%"TAP"
"1","(3225,2300)","0","standard","I127";
;
CDS_LIB"standard"
BODY_TYPE"PLUMBING"
HDL_TAP"TRUE";
"B \NAC \NWC"7;
"S \NAC"
BN"8"118;
%"TAP"
"1","(3225,2250)","0","standard","I128";
;
CDS_LIB"standard"
BODY_TYPE"PLUMBING"
HDL_TAP"TRUE";
"B \NAC \NWC"7;
"S \NAC"
BN"7"117;
%"TAP"
"1","(3225,2450)","0","standard","I129";
;
CDS_LIB"standard"
BODY_TYPE"PLUMBING"
HDL_TAP"TRUE";
"B \NAC \NWC"8;
"S \NAC"
BN"0"100;
%"TAP"
"1","(-200,250)","2","standard","I13";
;
CDS_LIB"standard"
BODY_TYPE"PLUMBING"
HDL_TAP"TRUE";
"B \NAC \NWC"9;
"S \NAC"
BN"3"95;
%"TAP"
"1","(3225,2500)","0","standard","I130";
;
CDS_LIB"standard"
BODY_TYPE"PLUMBING"
HDL_TAP"TRUE";
"B \NAC \NWC"8;
"S \NAC"
BN"1"101;
%"TAP"
"1","(3225,2550)","0","standard","I131";
;
CDS_LIB"standard"
BODY_TYPE"PLUMBING"
HDL_TAP"TRUE";
"B \NAC \NWC"8;
"S \NAC"
BN"2"102;
%"TAP"
"1","(3225,2600)","0","standard","I132";
;
CDS_LIB"standard"
BODY_TYPE"PLUMBING"
HDL_TAP"TRUE";
"B \NAC \NWC"8;
"S \NAC"
BN"3"103;
%"TAP"
"1","(3225,2750)","0","standard","I133";
;
CDS_LIB"standard"
BODY_TYPE"PLUMBING"
HDL_TAP"TRUE";
"B \NAC \NWC"8;
"S \NAC"
BN"6"106;
%"TAP"
"1","(3225,2650)","0","standard","I134";
;
CDS_LIB"standard"
BODY_TYPE"PLUMBING"
HDL_TAP"TRUE";
"B \NAC \NWC"8;
"S \NAC"
BN"4"104;
%"TAP"
"1","(3225,2700)","0","standard","I135";
;
CDS_LIB"standard"
BODY_TYPE"PLUMBING"
HDL_TAP"TRUE";
"B \NAC \NWC"8;
"S \NAC"
BN"5"105;
%"TAP"
"1","(3225,2850)","0","standard","I136";
;
CDS_LIB"standard"
BODY_TYPE"PLUMBING"
HDL_TAP"TRUE";
"B \NAC \NWC"8;
"S \NAC"
BN"8"108;
%"TAP"
"1","(3225,2900)","0","standard","I137";
;
CDS_LIB"standard"
BODY_TYPE"PLUMBING"
HDL_TAP"TRUE";
"B \NAC \NWC"8;
"S \NAC"
BN"9"109;
%"TAP"
"1","(3225,2800)","0","standard","I138";
;
CDS_LIB"standard"
BODY_TYPE"PLUMBING"
HDL_TAP"TRUE";
"B \NAC \NWC"8;
"S \NAC"
BN"7"107;
%"TAP"
"1","(3225,3100)","0","standard","I139";
;
CDS_LIB"standard"
BODY_TYPE"PLUMBING"
HDL_TAP"TRUE";
"B \NAC \NWC"3;
"S \NAC"
BN"1"143;
%"TAP"
"1","(-200,400)","2","standard","I14";
;
CDS_LIB"standard"
BODY_TYPE"PLUMBING"
HDL_TAP"TRUE";
"B \NAC \NWC"9;
"S \NAC"
BN"6"92;
%"TAP"
"1","(3225,3050)","0","standard","I140";
;
CDS_LIB"standard"
BODY_TYPE"PLUMBING"
HDL_TAP"TRUE";
"B \NAC \NWC"3;
"S \NAC"
BN"0"142;
%"TAP"
"1","(3225,3250)","0","standard","I141";
;
CDS_LIB"standard"
BODY_TYPE"PLUMBING"
HDL_TAP"TRUE";
"B \NAC \NWC"3;
"S \NAC"
BN"4"146;
%"TAP"
"1","(3225,3150)","0","standard","I142";
;
CDS_LIB"standard"
BODY_TYPE"PLUMBING"
HDL_TAP"TRUE";
"B \NAC \NWC"3;
"S \NAC"
BN"2"144;
%"TAP"
"1","(3225,3200)","0","standard","I143";
;
CDS_LIB"standard"
BODY_TYPE"PLUMBING"
HDL_TAP"TRUE";
"B \NAC \NWC"3;
"S \NAC"
BN"3"145;
%"TAP"
"1","(3225,3300)","0","standard","I144";
;
CDS_LIB"standard"
BODY_TYPE"PLUMBING"
HDL_TAP"TRUE";
"B \NAC \NWC"3;
"S \NAC"
BN"5"147;
%"TAP"
"1","(3225,3350)","0","standard","I145";
;
CDS_LIB"standard"
BODY_TYPE"PLUMBING"
HDL_TAP"TRUE";
"B \NAC \NWC"3;
"S \NAC"
BN"6"148;
%"TAP"
"1","(3225,3400)","0","standard","I146";
;
CDS_LIB"standard"
BODY_TYPE"PLUMBING"
HDL_TAP"TRUE";
"B \NAC \NWC"3;
"S \NAC"
BN"7"149;
%"TAP"
"1","(3225,3500)","0","standard","I147";
;
CDS_LIB"standard"
BODY_TYPE"PLUMBING"
HDL_TAP"TRUE";
"B \NAC \NWC"3;
"S \NAC"
BN"9"151;
%"TAP"
"1","(3225,3450)","0","standard","I148";
;
CDS_LIB"standard"
BODY_TYPE"PLUMBING"
HDL_TAP"TRUE";
"B \NAC \NWC"3;
"S \NAC"
BN"8"150;
%"TAP"
"1","(3225,3600)","0","standard","I149";
;
CDS_LIB"standard"
BODY_TYPE"PLUMBING"
HDL_TAP"TRUE";
"B \NAC \NWC"4;
"S \NAC"
BN"0"132;
%"TAP"
"1","(-200,350)","2","standard","I15";
;
CDS_LIB"standard"
BODY_TYPE"PLUMBING"
HDL_TAP"TRUE";
"B \NAC \NWC"9;
"S \NAC"
BN"5"93;
%"TAP"
"1","(3225,3650)","0","standard","I150";
;
CDS_LIB"standard"
BODY_TYPE"PLUMBING"
HDL_TAP"TRUE";
"B \NAC \NWC"4;
"S \NAC"
BN"1"133;
%"TAP"
"1","(3225,3750)","0","standard","I151";
;
CDS_LIB"standard"
BODY_TYPE"PLUMBING"
HDL_TAP"TRUE";
"B \NAC \NWC"4;
"S \NAC"
BN"3"135;
%"TAP"
"1","(3225,3700)","0","standard","I152";
;
CDS_LIB"standard"
BODY_TYPE"PLUMBING"
HDL_TAP"TRUE";
"B \NAC \NWC"4;
"S \NAC"
BN"2"134;
%"TAP"
"1","(3225,3800)","0","standard","I153";
;
CDS_LIB"standard"
BODY_TYPE"PLUMBING"
HDL_TAP"TRUE";
"B \NAC \NWC"4;
"S \NAC"
BN"4"136;
%"TAP"
"1","(3225,3850)","0","standard","I154";
;
CDS_LIB"standard"
BODY_TYPE"PLUMBING"
HDL_TAP"TRUE";
"B \NAC \NWC"4;
"S \NAC"
BN"5"137;
%"TAP"
"1","(3225,3900)","0","standard","I155";
;
CDS_LIB"standard"
BODY_TYPE"PLUMBING"
HDL_TAP"TRUE";
"B \NAC \NWC"4;
"S \NAC"
BN"6"138;
%"TAP"
"1","(3225,4000)","0","standard","I156";
;
CDS_LIB"standard"
BODY_TYPE"PLUMBING"
HDL_TAP"TRUE";
"B \NAC \NWC"4;
"S \NAC"
BN"8"140;
%"TAP"
"1","(3225,3950)","0","standard","I157";
;
CDS_LIB"standard"
BODY_TYPE"PLUMBING"
HDL_TAP"TRUE";
"B \NAC \NWC"4;
"S \NAC"
BN"7"139;
%"TAP"
"1","(3225,4050)","0","standard","I158";
;
CDS_LIB"standard"
BODY_TYPE"PLUMBING"
HDL_TAP"TRUE";
"B \NAC \NWC"4;
"S \NAC"
BN"9"141;
%"TAP"
"1","(-200,500)","2","standard","I16";
;
CDS_LIB"standard"
BODY_TYPE"PLUMBING"
HDL_TAP"TRUE";
"B \NAC \NWC"10;
"S \NAC"
BN"0"90;
%"SOCKET4677_AZIF0045P001C01CS"
"14","(1525,1950)","0","pure_quanta","I169";
;
PART_NUMBER"DGA^7000023"
PART_TYPE"SMLF"
MATERIAL"IO"
VALUE"SOCKET4677_AZIF0045-P001C01CS"
$LOCATION"U2"
CDS_LIB"pure_quanta"
NEEDS_NO_SIZE"TRUE"
CDS_LMAN_SYM_OUTLINE"-1100,2250,1050,-2250"
CDS_LOCATION"U2"
$SEC"14"
CDS_SEC"14";
"DDR6_SB_PAR"
$PN"EB42"99;
"DDR6_SB_ECC0"
$PN"DU35"98;
"DDR6_SB_ECC1"
$PN"DV34"97;
"DDR6_SB_ECC2"
$PN"EA35"96;
"DDR6_SB_ECC3"
$PN"DY34"95;
"DDR6_SB_ECC4"
$PN"DV38"94;
"DDR6_SB_ECC5"
$PN"DU37"93;
"DDR6_SB_ECC6"
$PN"DY38"92;
"DDR6_SB_ECC7"
$PN"EA37"91;
"DDR6_SB_DQS_DP0"
$PN"DL33"100;
"DDR6_SB_DQS_DP1"
$PN"DL27"101;
"DDR6_SB_DQS_DP2"
$PN"DT24"102;
"DDR6_SB_DQS_DP3"
$PN"EN7"103;
"DDR6_SB_DQS_DP4"
$PN"DY36"104;
"DDR6_SB_DQS_DP5"
$PN"DN33"105;
"DDR6_SB_DQS_DP6"
$PN"DR27"106;
"DDR6_SB_DQS_DP7"
$PN"DY24"107;
"DDR6_SB_DQS_DP8"
$PN"EN5"108;
"DDR6_SB_DQS_DP9"
$PN"DT36"109;
"DDR6_SB_DQS_DN0 \B"
$PN"DJ33"110;
"DDR6_SB_DQS_DN1 \B"
$PN"DJ27"111;
"DDR6_SB_DQS_DN2 \B"
$PN"DV24"112;
"DDR6_SB_DQS_DN3 \B"
$PN"EP6"113;
"DDR6_SB_DQS_DN4 \B"
$PN"EB36"114;
"DDR6_SB_DQS_DN5 \B"
$PN"DR33"115;
"DDR6_SB_DQS_DN6 \B"
$PN"DN27"116;
"DDR6_SB_DQS_DN7 \B"
$PN"EB24"117;
"DDR6_SB_DQS_DN8 \B"
$PN"EM6"118;
"DDR6_SB_DQS_DN9 \B"
$PN"DV36"119;
"DDR6_SB_DQ0"
$PN"DL35"90;
"DDR6_SB_DQ1"
$PN"DK34"89;
"DDR6_SB_DQ2"
$PN"DN35"88;
"DDR6_SB_DQ3"
$PN"DP34"87;
"DDR6_SB_DQ4"
$PN"DK32"86;
"DDR6_SB_DQ5"
$PN"DL31"85;
"DDR6_SB_DQ6"
$PN"DP32"84;
"DDR6_SB_DQ7"
$PN"DN31"83;
"DDR6_SB_DQ8"
$PN"DN29"82;
"DDR6_SB_DQ9"
$PN"DK28"81;
"DDR6_SB_DQ10"
$PN"DL29"80;
"DDR6_SB_DQ11"
$PN"DP28"79;
"DDR6_SB_DQ12"
$PN"DK26"78;
"DDR6_SB_DQ13"
$PN"DL25"77;
"DDR6_SB_DQ14"
$PN"DP26"76;
"DDR6_SB_DQ15"
$PN"DN25"75;
"DDR6_SB_DQ16"
$PN"DV26"74;
"DDR6_SB_DQ17"
$PN"DU25"73;
"DDR6_SB_DQ18"
$PN"DY26"72;
"DDR6_SB_DQ19"
$PN"EA25"71;
"DDR6_SB_DQ20"
$PN"DU23"70;
"DDR6_SB_DQ21"
$PN"DV22"69;
"DDR6_SB_DQ22"
$PN"EA23"68;
"DDR6_SB_DQ23"
$PN"DY22"67;
"DDR6_SB_DQ24"
$PN"EK8"66;
"DDR6_SB_DQ25"
$PN"EH8"65;
"DDR6_SB_DQ26"
$PN"EP8"64;
"DDR6_SB_DQ27"
$PN"ET8"63;
"DDR6_SB_DQ28"
$PN"EK6"62;
"DDR6_SB_DQ29"
$PN"EJ5"61;
"DDR6_SB_DQ30"
$PN"EP4"60;
"DDR6_SB_DQ31"
$PN"EM4"59;
"DDR6_SB_CS_N0 \B"
$PN"EA41"120;
"DDR6_SB_CS_N1 \B"
$PN"DY40"121;
"DDR6_SB_CS_N2 \B"
$PN"DU41"122;
"DDR6_SB_CS_N3 \B"
$PN"DV40"123;
"DDR6_SB_CA0"
$PN"DN43"124;
"DDR6_SB_CA1"
$PN"DP44"125;
"DDR6_SB_CA2"
$PN"DV44"126;
"DDR6_SB_CA3"
$PN"DY44"127;
"DDR6_SB_CA4"
$PN"DU43"128;
"DDR6_SB_CA5"
$PN"EA43"129;
"DDR6_SB_CA6"
$PN"DT42"130;
"DDR6_SA_PAR"
$PN"DL43"131;
"DDR6_SA_ECC0"
$PN"DL60"58;
"DDR6_SA_ECC1"
$PN"DK59"57;
"DDR6_SA_ECC2"
$PN"DN60"56;
"DDR6_SA_ECC3"
$PN"DP59"55;
"DDR6_SA_ECC4"
$PN"DK57"54;
"DDR6_SA_ECC5"
$PN"DL56"53;
"DDR6_SA_ECC6"
$PN"DP57"52;
"DDR6_SA_ECC7"
$PN"DN56"51;
"DDR6_SA_DQS_DP0"
$PN"DT73"132;
"DDR6_SA_DQS_DP1"
$PN"DL70"133;
"DDR6_SA_DQS_DP2"
$PN"DV61"134;
"DDR6_SA_DQS_DP3"
$PN"DJ64"135;
"DDR6_SA_DQS_DP4"
$PN"DJ58"136;
"DDR6_SA_DQS_DP5"
$PN"DY73"137;
"DDR6_SA_DQS_DP6"
$PN"DN70"138;
"DDR6_SA_DQS_DP7"
$PN"DY61"139;
"DDR6_SA_DQS_DP8"
$PN"DN64"140;
"DDR6_SA_DQS_DP9"
$PN"DN58"141;
"DDR6_SA_DQS_DN0 \B"
$PN"DV73"142;
"DDR6_SA_DQS_DN1 \B"
$PN"DJ70"143;
"DDR6_SA_DQS_DN2 \B"
$PN"DT61"144;
"DDR6_SA_DQS_DN3 \B"
$PN"DL64"145;
"DDR6_SA_DQS_DN4 \B"
$PN"DL58"146;
"DDR6_SA_DQS_DN5 \B"
$PN"EB73"147;
"DDR6_SA_DQS_DN6 \B"
$PN"DR70"148;
"DDR6_SA_DQS_DN7 \B"
$PN"EB61"149;
"DDR6_SA_DQS_DN8 \B"
$PN"DR64"150;
"DDR6_SA_DQS_DN9 \B"
$PN"DR58"151;
"DDR6_SA_DQ0"
$PN"DV75"50;
"DDR6_SA_DQ1"
$PN"DU74"49;
"DDR6_SA_DQ2"
$PN"DY75"48;
"DDR6_SA_DQ3"
$PN"EA74"47;
"DDR6_SA_DQ4"
$PN"DU72"46;
"DDR6_SA_DQ5"
$PN"DV71"45;
"DDR6_SA_DQ6"
$PN"EA72"44;
"DDR6_SA_DQ7"
$PN"DY71"43;
"DDR6_SA_DQ8"
$PN"DL72"42;
"DDR6_SA_DQ9"
$PN"DK71"41;
"DDR6_SA_DQ10"
$PN"DN72"40;
"DDR6_SA_DQ11"
$PN"DP71"39;
"DDR6_SA_DQ12"
$PN"DK69"38;
"DDR6_SA_DQ13"
$PN"DL68"37;
"DDR6_SA_DQ14"
$PN"DP69"36;
"DDR6_SA_DQ15"
$PN"DN68"35;
"DDR6_SA_DQ16"
$PN"DV63"34;
"DDR6_SA_DQ17"
$PN"DU62"33;
"DDR6_SA_DQ18"
$PN"DY63"32;
"DDR6_SA_DQ19"
$PN"EA62"31;
"DDR6_SA_DQ20"
$PN"DU60"30;
"DDR6_SA_DQ21"
$PN"DV59"29;
"DDR6_SA_DQ22"
$PN"EA60"28;
"DDR6_SA_DQ23"
$PN"DY59"27;
"DDR6_SA_DQ24"
$PN"DL66"26;
"DDR6_SA_DQ25"
$PN"DK65"25;
"DDR6_SA_DQ26"
$PN"DN66"24;
"DDR6_SA_DQ27"
$PN"DP65"23;
"DDR6_SA_DQ28"
$PN"DK63"22;
"DDR6_SA_DQ29"
$PN"DL62"21;
"DDR6_SA_DQ30"
$PN"DP63"20;
"DDR6_SA_DQ31"
$PN"DN62"19;
"DDR6_SA_CS_N0 \B"
$PN"DN54"152;
"DDR6_SA_CS_N1 \B"
$PN"DP53"153;
"DDR6_SA_CS_N2 \B"
$PN"DL54"154;
"DDR6_SA_CS_N3 \B"
$PN"DK53"155;
"DDR6_SA_CA0"
$PN"DJ52"156;
"DDR6_SA_CA1"
$PN"DR52"157;
"DDR6_SA_CA2"
$PN"DK51"158;
"DDR6_SA_CA3"
$PN"DP51"159;
"DDR6_SA_CA4"
$PN"DL50"160;
"DDR6_SA_CA5"
$PN"DN50"161;
"DDR6_SA_CA6"
$PN"DK44"162;
"DDR6_CLK_DP0"
$PN"DN45"18;
"DDR6_CLK_DP1"
$PN"DJ45"17;
"DDR6_CLK_DN0 \B"
$PN"DR45"16;
"DDR6_CLK_DN1 \B"
$PN"DL45"15;
"DDR6_B_RSP0"
$PN"DU48"163;
"DDR6_B_RSP1"
$PN"DV47"164;
"DDR6_A_RSP0"
$PN"EA48"165;
"DDR6_A_RSP1"
$PN"DY47"166;
"DDR6_ALERT_N \B"
$PN"CW50"167;
%"TAP"
"1","(-200,450)","2","standard","I17";
;
CDS_LIB"standard"
BODY_TYPE"PLUMBING"
HDL_TAP"TRUE";
"B \NAC \NWC"9;
"S \NAC"
BN"7"91;
%"TAP"
"1","(-200,550)","2","standard","I18";
;
CDS_LIB"standard"
BODY_TYPE"PLUMBING"
HDL_TAP"TRUE";
"B \NAC \NWC"10;
"S \NAC"
BN"1"89;
%"TAP"
"1","(-200,650)","2","standard","I19";
;
CDS_LIB"standard"
BODY_TYPE"PLUMBING"
HDL_TAP"TRUE";
"B \NAC \NWC"10;
"S \NAC"
BN"3"87;
%"TAP"
"1","(-200,600)","2","standard","I20";
;
CDS_LIB"standard"
BODY_TYPE"PLUMBING"
HDL_TAP"TRUE";
"B \NAC \NWC"10;
"S \NAC"
BN"2"88;
%"TAP"
"1","(-200,700)","2","standard","I21";
;
CDS_LIB"standard"
BODY_TYPE"PLUMBING"
HDL_TAP"TRUE";
"B \NAC \NWC"10;
"S \NAC"
BN"4"86;
%"TAP"
"1","(-200,800)","2","standard","I22";
;
CDS_LIB"standard"
BODY_TYPE"PLUMBING"
HDL_TAP"TRUE";
"B \NAC \NWC"10;
"S \NAC"
BN"6"84;
%"TAP"
"1","(-200,750)","2","standard","I23";
;
CDS_LIB"standard"
BODY_TYPE"PLUMBING"
HDL_TAP"TRUE";
"B \NAC \NWC"10;
"S \NAC"
BN"5"85;
%"TAP"
"1","(-200,900)","2","standard","I24";
;
CDS_LIB"standard"
BODY_TYPE"PLUMBING"
HDL_TAP"TRUE";
"B \NAC \NWC"10;
"S \NAC"
BN"8"82;
%"TAP"
"1","(-200,850)","2","standard","I25";
;
CDS_LIB"standard"
BODY_TYPE"PLUMBING"
HDL_TAP"TRUE";
"B \NAC \NWC"10;
"S \NAC"
BN"7"83;
%"TAP"
"1","(-200,950)","2","standard","I26";
;
CDS_LIB"standard"
BODY_TYPE"PLUMBING"
HDL_TAP"TRUE";
"B \NAC \NWC"10;
"S \NAC"
BN"9"81;
%"TAP"
"1","(-200,1000)","2","standard","I27";
;
CDS_LIB"standard"
BODY_TYPE"PLUMBING"
HDL_TAP"TRUE";
"B \NAC \NWC"10;
"S \NAC"
BN"10"80;
%"TAP"
"1","(-200,1050)","2","standard","I28";
;
CDS_LIB"standard"
BODY_TYPE"PLUMBING"
HDL_TAP"TRUE";
"B \NAC \NWC"10;
"S \NAC"
BN"11"79;
%"TAP"
"1","(-200,1150)","2","standard","I29";
;
CDS_LIB"standard"
BODY_TYPE"PLUMBING"
HDL_TAP"TRUE";
"B \NAC \NWC"10;
"S \NAC"
BN"13"77;
%"TAP"
"1","(-200,-100)","2","standard","I3";
;
CDS_LIB"standard"
BODY_TYPE"PLUMBING"
HDL_TAP"TRUE";
"B \NAC \NWC"14;
"S \NAC"
BN"1"15;
%"TAP"
"1","(-200,1100)","2","standard","I30";
;
CDS_LIB"standard"
BODY_TYPE"PLUMBING"
HDL_TAP"TRUE";
"B \NAC \NWC"10;
"S \NAC"
BN"12"78;
%"TAP"
"1","(-200,1200)","2","standard","I31";
;
CDS_LIB"standard"
BODY_TYPE"PLUMBING"
HDL_TAP"TRUE";
"B \NAC \NWC"10;
"S \NAC"
BN"14"76;
%"TAP"
"1","(-200,1250)","2","standard","I32";
;
CDS_LIB"standard"
BODY_TYPE"PLUMBING"
HDL_TAP"TRUE";
"B \NAC \NWC"10;
"S \NAC"
BN"15"75;
%"TAP"
"1","(-200,1300)","2","standard","I33";
;
CDS_LIB"standard"
BODY_TYPE"PLUMBING"
HDL_TAP"TRUE";
"B \NAC \NWC"10;
"S \NAC"
BN"16"74;
%"TAP"
"1","(-200,1400)","2","standard","I34";
;
CDS_LIB"standard"
BODY_TYPE"PLUMBING"
HDL_TAP"TRUE";
"B \NAC \NWC"10;
"S \NAC"
BN"18"72;
%"TAP"
"1","(-200,1450)","2","standard","I35";
;
CDS_LIB"standard"
BODY_TYPE"PLUMBING"
HDL_TAP"TRUE";
"B \NAC \NWC"10;
"S \NAC"
BN"19"71;
%"TAP"
"1","(-200,1350)","2","standard","I36";
;
CDS_LIB"standard"
BODY_TYPE"PLUMBING"
HDL_TAP"TRUE";
"B \NAC \NWC"10;
"S \NAC"
BN"17"73;
%"TAP"
"1","(-200,1550)","2","standard","I37";
;
CDS_LIB"standard"
BODY_TYPE"PLUMBING"
HDL_TAP"TRUE";
"B \NAC \NWC"10;
"S \NAC"
BN"21"69;
%"TAP"
"1","(-200,1500)","2","standard","I38";
;
CDS_LIB"standard"
BODY_TYPE"PLUMBING"
HDL_TAP"TRUE";
"B \NAC \NWC"10;
"S \NAC"
BN"20"70;
%"TAP"
"1","(-200,1600)","2","standard","I39";
;
CDS_LIB"standard"
BODY_TYPE"PLUMBING"
HDL_TAP"TRUE";
"B \NAC \NWC"10;
"S \NAC"
BN"22"68;
%"TAP"
"1","(-200,-150)","2","standard","I4";
;
CDS_LIB"standard"
BODY_TYPE"PLUMBING"
HDL_TAP"TRUE";
"B \NAC \NWC"14;
"S \NAC"
BN"0"16;
%"TAP"
"1","(-200,1650)","2","standard","I40";
;
CDS_LIB"standard"
BODY_TYPE"PLUMBING"
HDL_TAP"TRUE";
"B \NAC \NWC"10;
"S \NAC"
BN"23"67;
%"TAP"
"1","(-200,1700)","2","standard","I41";
;
CDS_LIB"standard"
BODY_TYPE"PLUMBING"
HDL_TAP"TRUE";
"B \NAC \NWC"10;
"S \NAC"
BN"24"66;
%"TAP"
"1","(-200,1750)","2","standard","I42";
;
CDS_LIB"standard"
BODY_TYPE"PLUMBING"
HDL_TAP"TRUE";
"B \NAC \NWC"10;
"S \NAC"
BN"25"65;
%"TAP"
"1","(-200,1800)","2","standard","I43";
;
CDS_LIB"standard"
BODY_TYPE"PLUMBING"
HDL_TAP"TRUE";
"B \NAC \NWC"10;
"S \NAC"
BN"26"64;
%"TAP"
"1","(-200,1850)","2","standard","I44";
;
CDS_LIB"standard"
BODY_TYPE"PLUMBING"
HDL_TAP"TRUE";
"B \NAC \NWC"10;
"S \NAC"
BN"27"63;
%"TAP"
"1","(-200,1900)","2","standard","I45";
;
CDS_LIB"standard"
BODY_TYPE"PLUMBING"
HDL_TAP"TRUE";
"B \NAC \NWC"10;
"S \NAC"
BN"28"62;
%"TAP"
"1","(-200,1950)","2","standard","I46";
;
CDS_LIB"standard"
BODY_TYPE"PLUMBING"
HDL_TAP"TRUE";
"B \NAC \NWC"10;
"S \NAC"
BN"29"61;
%"TAP"
"1","(-200,2050)","2","standard","I47";
;
CDS_LIB"standard"
BODY_TYPE"PLUMBING"
HDL_TAP"TRUE";
"B \NAC \NWC"10;
"S \NAC"
BN"31"59;
%"TAP"
"1","(-200,2000)","2","standard","I48";
;
CDS_LIB"standard"
BODY_TYPE"PLUMBING"
HDL_TAP"TRUE";
"B \NAC \NWC"10;
"S \NAC"
BN"30"60;
%"TAP"
"1","(-200,2200)","2","standard","I49";
;
CDS_LIB"standard"
BODY_TYPE"PLUMBING"
HDL_TAP"TRUE";
"B \NAC \NWC"11;
"S \NAC"
BN"2"56;
%"TAP"
"1","(-200,150)","2","standard","I5";
;
CDS_LIB"standard"
BODY_TYPE"PLUMBING"
HDL_TAP"TRUE";
"B \NAC \NWC"9;
"S \NAC"
BN"1"97;
%"TAP"
"1","(-200,2150)","2","standard","I50";
;
CDS_LIB"standard"
BODY_TYPE"PLUMBING"
HDL_TAP"TRUE";
"B \NAC \NWC"11;
"S \NAC"
BN"1"57;
%"TAP"
"1","(-200,2100)","2","standard","I51";
;
CDS_LIB"standard"
BODY_TYPE"PLUMBING"
HDL_TAP"TRUE";
"B \NAC \NWC"11;
"S \NAC"
BN"0"58;
%"TAP"
"1","(-200,2300)","2","standard","I54";
;
CDS_LIB"standard"
BODY_TYPE"PLUMBING"
HDL_TAP"TRUE";
"B \NAC \NWC"11;
"S \NAC"
BN"4"54;
%"TAP"
"1","(-200,2350)","2","standard","I55";
;
CDS_LIB"standard"
BODY_TYPE"PLUMBING"
HDL_TAP"TRUE";
"B \NAC \NWC"11;
"S \NAC"
BN"5"53;
%"TAP"
"1","(-200,2250)","2","standard","I56";
;
CDS_LIB"standard"
BODY_TYPE"PLUMBING"
HDL_TAP"TRUE";
"B \NAC \NWC"11;
"S \NAC"
BN"3"55;
%"TAP"
"1","(-200,2450)","2","standard","I57";
;
CDS_LIB"standard"
BODY_TYPE"PLUMBING"
HDL_TAP"TRUE";
"B \NAC \NWC"11;
"S \NAC"
BN"7"51;
%"TAP"
"1","(-200,2400)","2","standard","I58";
;
CDS_LIB"standard"
BODY_TYPE"PLUMBING"
HDL_TAP"TRUE";
"B \NAC \NWC"11;
"S \NAC"
BN"6"52;
%"TAP"
"1","(-200,2550)","2","standard","I59";
;
CDS_LIB"standard"
BODY_TYPE"PLUMBING"
HDL_TAP"TRUE";
"B \NAC \NWC"12;
"S \NAC"
BN"1"49;
%"TAP"
"1","(-200,100)","2","standard","I6";
;
CDS_LIB"standard"
BODY_TYPE"PLUMBING"
HDL_TAP"TRUE";
"B \NAC \NWC"9;
"S \NAC"
BN"0"98;
%"TAP"
"1","(-200,2500)","2","standard","I60";
;
CDS_LIB"standard"
BODY_TYPE"PLUMBING"
HDL_TAP"TRUE";
"B \NAC \NWC"12;
"S \NAC"
BN"0"50;
%"TAP"
"1","(-200,2600)","2","standard","I61";
;
CDS_LIB"standard"
BODY_TYPE"PLUMBING"
HDL_TAP"TRUE";
"B \NAC \NWC"12;
"S \NAC"
BN"2"48;
%"TAP"
"1","(-200,2700)","2","standard","I62";
;
CDS_LIB"standard"
BODY_TYPE"PLUMBING"
HDL_TAP"TRUE";
"B \NAC \NWC"12;
"S \NAC"
BN"4"46;
%"TAP"
"1","(-200,2650)","2","standard","I63";
;
CDS_LIB"standard"
BODY_TYPE"PLUMBING"
HDL_TAP"TRUE";
"B \NAC \NWC"12;
"S \NAC"
BN"3"47;
%"TAP"
"1","(-200,2750)","2","standard","I64";
;
CDS_LIB"standard"
BODY_TYPE"PLUMBING"
HDL_TAP"TRUE";
"B \NAC \NWC"12;
"S \NAC"
BN"5"45;
%"TAP"
"1","(-200,2850)","2","standard","I65";
;
CDS_LIB"standard"
BODY_TYPE"PLUMBING"
HDL_TAP"TRUE";
"B \NAC \NWC"12;
"S \NAC"
BN"7"43;
%"TAP"
"1","(-200,2800)","2","standard","I66";
;
CDS_LIB"standard"
BODY_TYPE"PLUMBING"
HDL_TAP"TRUE";
"B \NAC \NWC"12;
"S \NAC"
BN"6"44;
%"TAP"
"1","(-200,2950)","2","standard","I67";
;
CDS_LIB"standard"
BODY_TYPE"PLUMBING"
HDL_TAP"TRUE";
"B \NAC \NWC"12;
"S \NAC"
BN"9"41;
%"TAP"
"1","(-200,2900)","2","standard","I68";
;
CDS_LIB"standard"
BODY_TYPE"PLUMBING"
HDL_TAP"TRUE";
"B \NAC \NWC"12;
"S \NAC"
BN"8"42;
%"TAP"
"1","(-200,3000)","2","standard","I69";
;
CDS_LIB"standard"
BODY_TYPE"PLUMBING"
HDL_TAP"TRUE";
"B \NAC \NWC"12;
"S \NAC"
BN"10"40;
%"TAP"
"1","(-200,-50)","2","standard","I7";
;
CDS_LIB"standard"
BODY_TYPE"PLUMBING"
HDL_TAP"TRUE";
"B \NAC \NWC"13;
"S \NAC"
BN"0"18;
%"TAP"
"1","(-200,3050)","2","standard","I70";
;
CDS_LIB"standard"
BODY_TYPE"PLUMBING"
HDL_TAP"TRUE";
"B \NAC \NWC"12;
"S \NAC"
BN"11"39;
%"TAP"
"1","(-200,3100)","2","standard","I71";
;
CDS_LIB"standard"
BODY_TYPE"PLUMBING"
HDL_TAP"TRUE";
"B \NAC \NWC"12;
"S \NAC"
BN"12"38;
%"TAP"
"1","(-200,3200)","2","standard","I72";
;
CDS_LIB"standard"
BODY_TYPE"PLUMBING"
HDL_TAP"TRUE";
"B \NAC \NWC"12;
"S \NAC"
BN"14"36;
%"TAP"
"1","(-200,3150)","2","standard","I73";
;
CDS_LIB"standard"
BODY_TYPE"PLUMBING"
HDL_TAP"TRUE";
"B \NAC \NWC"12;
"S \NAC"
BN"13"37;
%"TAP"
"1","(-200,3250)","2","standard","I74";
;
CDS_LIB"standard"
BODY_TYPE"PLUMBING"
HDL_TAP"TRUE";
"B \NAC \NWC"12;
"S \NAC"
BN"15"35;
%"TAP"
"1","(-200,3300)","2","standard","I75";
;
CDS_LIB"standard"
BODY_TYPE"PLUMBING"
HDL_TAP"TRUE";
"B \NAC \NWC"12;
"S \NAC"
BN"16"34;
%"TAP"
"1","(-200,3350)","2","standard","I76";
;
CDS_LIB"standard"
BODY_TYPE"PLUMBING"
HDL_TAP"TRUE";
"B \NAC \NWC"12;
"S \NAC"
BN"17"33;
%"TAP"
"1","(-200,3450)","2","standard","I77";
;
CDS_LIB"standard"
BODY_TYPE"PLUMBING"
HDL_TAP"TRUE";
"B \NAC \NWC"12;
"S \NAC"
BN"19"31;
%"TAP"
"1","(-200,3500)","2","standard","I78";
;
CDS_LIB"standard"
BODY_TYPE"PLUMBING"
HDL_TAP"TRUE";
"B \NAC \NWC"12;
"S \NAC"
BN"20"30;
%"TAP"
"1","(-200,3400)","2","standard","I79";
;
CDS_LIB"standard"
BODY_TYPE"PLUMBING"
HDL_TAP"TRUE";
"B \NAC \NWC"12;
"S \NAC"
BN"18"32;
%"TAP"
"1","(-200,0)","2","standard","I8";
;
CDS_LIB"standard"
BODY_TYPE"PLUMBING"
HDL_TAP"TRUE";
"B \NAC \NWC"13;
"S \NAC"
BN"1"17;
%"TAP"
"1","(-200,3600)","2","standard","I80";
;
CDS_LIB"standard"
BODY_TYPE"PLUMBING"
HDL_TAP"TRUE";
"B \NAC \NWC"12;
"S \NAC"
BN"22"28;
%"TAP"
"1","(-200,3550)","2","standard","I81";
;
CDS_LIB"standard"
BODY_TYPE"PLUMBING"
HDL_TAP"TRUE";
"B \NAC \NWC"12;
"S \NAC"
BN"21"29;
%"TAP"
"1","(-200,3700)","2","standard","I82";
;
CDS_LIB"standard"
BODY_TYPE"PLUMBING"
HDL_TAP"TRUE";
"B \NAC \NWC"12;
"S \NAC"
BN"24"26;
%"TAP"
"1","(-200,3650)","2","standard","I83";
;
CDS_LIB"standard"
BODY_TYPE"PLUMBING"
HDL_TAP"TRUE";
"B \NAC \NWC"12;
"S \NAC"
BN"23"27;
%"TAP"
"1","(-200,3750)","2","standard","I84";
;
CDS_LIB"standard"
BODY_TYPE"PLUMBING"
HDL_TAP"TRUE";
"B \NAC \NWC"12;
"S \NAC"
BN"25"25;
%"TAP"
"1","(-200,3850)","2","standard","I85";
;
CDS_LIB"standard"
BODY_TYPE"PLUMBING"
HDL_TAP"TRUE";
"B \NAC \NWC"12;
"S \NAC"
BN"27"23;
%"TAP"
"1","(-200,3800)","2","standard","I86";
;
CDS_LIB"standard"
BODY_TYPE"PLUMBING"
HDL_TAP"TRUE";
"B \NAC \NWC"12;
"S \NAC"
BN"26"24;
%"TAP"
"1","(-200,3900)","2","standard","I87";
;
CDS_LIB"standard"
BODY_TYPE"PLUMBING"
HDL_TAP"TRUE";
"B \NAC \NWC"12;
"S \NAC"
BN"28"22;
%"TAP"
"1","(-200,3950)","2","standard","I88";
;
CDS_LIB"standard"
BODY_TYPE"PLUMBING"
HDL_TAP"TRUE";
"B \NAC \NWC"12;
"S \NAC"
BN"29"21;
%"TAP"
"1","(-200,4000)","2","standard","I89";
;
CDS_LIB"standard"
BODY_TYPE"PLUMBING"
HDL_TAP"TRUE";
"B \NAC \NWC"12;
"S \NAC"
BN"30"20;
%"TAP"
"1","(-200,200)","2","standard","I9";
;
CDS_LIB"standard"
BODY_TYPE"PLUMBING"
HDL_TAP"TRUE";
"B \NAC \NWC"9;
"S \NAC"
BN"2"96;
%"TAP"
"1","(-200,4050)","2","standard","I90";
;
CDS_LIB"standard"
BODY_TYPE"PLUMBING"
HDL_TAP"TRUE";
"B \NAC \NWC"12;
"S \NAC"
BN"31"19;
%"TAP"
"1","(3225,300)","0","standard","I97";
;
CDS_LIB"standard"
BODY_TYPE"PLUMBING"
HDL_TAP"TRUE";
"B \NAC \NWC"6;
"S \NAC"
BN"0"120;
%"TAP"
"1","(3225,450)","0","standard","I98";
;
CDS_LIB"standard"
BODY_TYPE"PLUMBING"
HDL_TAP"TRUE";
"B \NAC \NWC"6;
"S \NAC"
BN"3"123;
%"TAP"
"1","(3225,350)","0","standard","I99";
;
CDS_LIB"standard"
BODY_TYPE"PLUMBING"
HDL_TAP"TRUE";
"B \NAC \NWC"6;
"S \NAC"
BN"1"121;
END.
